#ISCELL
  mstr_misc dns *
  *
#ISCELL
  pure_quanta quanta_title_block_c *
  *
#ISCELL
  standard offpage *
  page286_i1
#CELL
  pure_quanta q_cap *
  page286_i10
#ISCELL
  logical_power universal_gnd *
  page286_i11
#CELL
  pure_quanta q_res *
  page286_i12
#CELL
  pure_quanta q_res *
  page286_i13
#CELL
  pure_quanta q_cap *
  page286_i14
#ISCELL
  logical_power universal_power *
  page286_i15
#CELL
  pure_quanta q_cap *
  page286_i16
#ISCELL
  logical_power universal_gnd *
  page286_i17
#ISCELL
  logical_power universal_gnd *
  page286_i18
#CELL
  pure_quanta q_res *
  page286_i19
#ISCELL
  logical_power vccaux15 *
  page286_i2
#CELL
  pure_quanta rs53317lr *
  page286_i20
#ISCELL
  logical_power universal_gnd *
  page286_i21
#CELL
  pure_quanta q_res *
  page286_i22
#CELL
  pure_quanta q_cap *
  page286_i23
#CELL
  pure_quanta q_cap *
  page286_i24
#CELL
  pure_quanta q_res *
  page286_i25
#CELL
  pure_quanta q_res *
  page286_i26
#CELL
  pure_quanta q_inductor *
  page286_i27
#CELL
  pure_quanta q_cap *
  page286_i28
#CELL
  pure_quanta q_res *
  page286_i29
#ISCELL
  logical_power universal_gnd *
  page286_i3
#ISCELL
  logical_power vccaux15 *
  page286_i30
#CELL
  pure_quanta q_res *
  page286_i31
#ISCELL
  logical_power universal_power *
  page286_i32
#CELL
  pure_quanta q_cap *
  page286_i33
#CELL
  pure_quanta q_res *
  page286_i34
#ISCELL
  logical_power universal_gnd *
  page286_i35
#CELL
  pure_quanta q_cap *
  page286_i36
#CELL
  pure_quanta q_cap *
  page286_i37
#CELL
  pure_quanta q_cap *
  page286_i38
#ISCELL
  standard offpage *
  page286_i39
#ISCELL
  logical_power universal_gnd *
  page286_i4
#CELL
  pure_quanta q_cap *
  page286_i40
#ISCELL
  logical_power universal_gnd *
  page286_i41
#CELL
  pure_quanta q_res *
  page286_i42
#CELL
  pure_quanta q_res *
  page286_i43
#CELL
  pure_quanta q_cap *
  page286_i44
#CELL
  pure_quanta q_cap *
  page286_i45
#ISCELL
  logical_power universal_gnd *
  page286_i46
#ISCELL
  logical_power universal_power *
  page286_i47
#ISCELL
  logical_power universal_power *
  page286_i48
#CELL
  pure_quanta q_res *
  page286_i5
#CELL
  pure_quanta q_cap *
  page286_i6
#CELL
  pure_quanta q_res *
  page286_i7
#ISCELL
  logical_power universal_gnd *
  page286_i8
#CELL
  pure_quanta q_cap *
  page286_i9
